# Stackup_F0T_FIO_4L_1p6mm_IT-170GT_RTF_Rev0p1_20211105.xls — Special processing (pcb-stackup)
| Special processing : |  |
| Golden Finger(金手指) | No |
| VIPPO(Via in Pad樹脂填孔) | No |
| Back Drill(背鑽) with epoxy plug/fill | No |
| Back Drill(背鑽) without epoxy plug/fill | No |
| Laser Drill(HDI雷射鑽孔) | No |
| Low profile oxide(低棕化) | No |
